;LEADER: 12 
;HEADER: 
;CODE  : ASCII 
;FILE  : 9332_F0TG_MB_C_V02_0417_0820-bd-18-4.drl for backdrilling ... from layer BOTTOM to layer GND1
;DESIGN: 9332_F0TG_MB_C_V02_0417_0820.brd
;MUST-NOT-CUT-LAYER = IN1,  MAX_DRILL_DEPTH = 83.60 MILS,  MFG_STUB_LENGTH = 0.00 MILS
;   BackdrillSize 1. = 14.800000 Tolerance = +0.000000/-0.000000 NON_PLATED MILS Quantity = 680
;   BackdrillSize 2. = 17.000000 Tolerance = +0.000000/-0.000000 NON_PLATED MILS Quantity = 612
%
G90
X0419059Y1152426
R02X-0011102
X0385752Y1152426
X0422760Y1152426
X0411658Y1152426
X0400555Y1152426
X0389453Y1152426
X0415358Y1158804
R02X-0011102
X0382051Y1158804
X0419059Y1158804
X0407957Y1158804
X0396855Y1158804
X0385752Y1158804
X1395201Y1152425
R02X-0011102
X1361894Y1152425
X1398902Y1152425
X1387800Y1152425
X1376697Y1152425
X1365595Y1152425
X1391500Y1158803
R02X-0011102
X1358193Y1158803
X1395201Y1158803
X1384099Y1158803
X1372997Y1158803
X1361894Y1158803
X0509704Y1053568
X0504153Y1044001
X0509704Y1066324
X0506003Y1149237
X0506003Y1130103
X0506003Y1110970
R02Y-0019134
X0509704Y1142859
X0509704Y1123726
X0509704Y1104592
X0509704Y1085458
X0511554Y1069513
X0504153Y1146048
X0504153Y1126915
X0504153Y1107781
R02Y-0019134
X0511554Y1146048
X0511554Y1126915
X0511554Y1107781
X0511554Y1088647
X0504153Y1101403
X0509704Y1098214
X0506003Y1098214
X0511554Y1095025
X0504153Y1095025
X0509704Y1091836
X0506003Y1085458
X0506003Y1155615
X0511554Y1152426
X0511554Y1082269
X0504153Y1152426
X0509704Y1149237
X0506003Y1142859
X0511554Y1139670
X0504153Y1139670
X0509704Y1136481
X0506003Y1136481
X0511554Y1133293
X0504153Y1133293
X0509704Y1130103
X0504153Y1082269
X0506003Y1123726
X0511554Y1120537
X0504153Y1120537
X0509704Y1117348
X0506003Y1117348
X0511554Y1114159
X0504153Y1114159
X0509704Y1110970
X0506003Y1104592
X0511554Y1101403
X0509704Y1079080
X0511554Y1050379
X0506003Y1047190
X0506003Y1066324
X0511554Y1063135
X0504153Y1063135
X0509704Y1059946
X0506003Y1079080
X0511554Y1075891
X0504153Y1075891
X0509704Y1072702
X0509704Y1040812
X0506003Y1040812
X0504153Y1037623
X0511554Y1037623
X0509704Y1034434
X0506003Y1034434
X0504153Y1031245
X0504153Y1050379
X0502971Y1007183
X0502971Y0975293
X0502971Y0956159
R02Y-0019134
X0502971Y0898758
X0510373Y0968915
R03Y-0019134
X0510373Y0892380
X0504822Y0972104
R03Y-0019134
X0504822Y0895569
X0508523Y0972104
R03Y-0019134
X0508523Y0895569
X0504822Y0908325
X0510373Y0905135
X0502971Y0905135
X0508523Y0901947
X0504822Y0901947
X0510373Y0898758
X0502971Y0892380
X0502971Y0962537
X0508523Y0959348
X0508523Y0889191
X0504822Y0959348
X0510373Y0956159
X0502971Y0949781
X0508523Y0946592
X0504822Y0946592
X0510373Y0943403
X0502971Y0943403
X0508523Y0940214
X0504822Y0940214
X0510373Y0937025
X0504822Y0889191
X0502971Y0930647
X0508523Y0927458
X0504822Y0927458
X0510373Y0924269
X0502971Y0924269
X0508523Y0921080
X0504822Y0921080
X0510373Y0917891
X0502971Y0911513
X0508523Y0908325
X0510373Y0886002
X0504822Y0991238
X0510373Y0988049
X0502971Y0981671
X0508523Y0978482
X0504822Y0978482
X0510373Y0975293
X0502971Y0968915
X0508523Y0965726
X0504822Y0965726
X0510373Y0962537
X0504822Y1003994
X0508523Y1003994
X0510373Y1000805
X0502971Y1000805
X0504822Y0997616
X0508523Y0997616
X0510373Y0994427
X0502971Y0988049
X0510373Y1007183
X0508523Y1010372
X0504822Y0984860
X1485846Y1053567
X1480295Y1044000
X1485846Y1066323
X1482145Y1149236
X1482145Y1130102
X1482145Y1110969
R02Y-0019134
X1485846Y1142858
X1485846Y1123725
X1485846Y1104591
X1485846Y1085457
X1487696Y1069512
X1480295Y1146047
X1480295Y1126914
X1480295Y1107780
R02Y-0019134
X1487696Y1146047
X1487696Y1126914
X1487696Y1107780
X1487696Y1088646
X1480295Y1101402
X1485846Y1098213
X1482145Y1098213
X1487696Y1095024
X1480295Y1095024
X1485846Y1091835
X1482145Y1085457
X1482145Y1155614
X1487696Y1152425
X1487696Y1082268
X1480295Y1152425
X1485846Y1149236
X1482145Y1142858
X1487696Y1139669
X1480295Y1139669
X1485846Y1136480
X1482145Y1136480
X1487696Y1133292
X1480295Y1133292
X1485846Y1130102
X1480295Y1082268
X1482145Y1123725
X1487696Y1120536
X1480295Y1120536
X1485846Y1117347
X1482145Y1117347
X1487696Y1114158
X1480295Y1114158
X1485846Y1110969
X1482145Y1104591
X1487696Y1101402
X1485846Y1079079
X1487696Y1050378
X1482145Y1047189
X1482145Y1066323
X1487696Y1063134
X1480295Y1063134
X1485846Y1059945
X1482145Y1079079
X1487696Y1075890
X1480295Y1075890
X1485846Y1072701
X1485846Y1040811
X1482145Y1040811
X1480295Y1037622
X1487696Y1037622
X1485846Y1034433
X1482145Y1034433
X1480295Y1031244
X1480295Y1050378
X1479113Y1007182
X1479113Y0975292
X1479113Y0956158
R02Y-0019134
X1479113Y0898757
X1486515Y0968914
R03Y-0019134
X1486515Y0892379
X1480964Y0972103
R03Y-0019134
X1480964Y0895568
X1484665Y0972103
R03Y-0019134
X1484665Y0895568
X1480964Y0908324
X1486515Y0905134
X1479113Y0905134
X1484665Y0901946
X1480964Y0901946
X1486515Y0898757
X1479113Y0892379
X1479113Y0962536
X1484665Y0959347
X1484665Y0889190
X1480964Y0959347
X1486515Y0956158
X1479113Y0949780
X1484665Y0946591
X1480964Y0946591
X1486515Y0943402
X1479113Y0943402
X1484665Y0940213
X1480964Y0940213
X1486515Y0937024
X1480964Y0889190
X1479113Y0930646
X1484665Y0927457
X1480964Y0927457
X1486515Y0924268
X1479113Y0924268
X1484665Y0921079
X1480964Y0921079
X1486515Y0917890
X1479113Y0911512
X1484665Y0908324
X1486515Y0886001
X1480964Y0991237
X1486515Y0988048
X1479113Y0981670
X1484665Y0978481
X1480964Y0978481
X1486515Y0975292
X1479113Y0968914
X1484665Y0965725
X1480964Y0965725
X1486515Y0962536
X1480964Y1003993
X1484665Y1003993
X1486515Y1000804
X1479113Y1000804
X1480964Y0997615
X1484665Y0997615
X1486515Y0994426
X1479113Y0988048
X1486515Y1007182
X1484665Y1010371
X1480964Y0984859
X0372799Y1053568
X0370949Y1044001
X0372799Y1066324
X0376500Y1149237
X0376500Y1130103
X0376500Y1110970
R02Y-0019134
X0372799Y1142859
X0372799Y1123726
X0372799Y1104592
X0372799Y1085458
X0370949Y1069513
X0378351Y1146048
X0378351Y1126915
X0378351Y1107781
R02Y-0019134
X0370949Y1146048
X0370949Y1126915
X0370949Y1107781
X0370949Y1088647
X0378351Y1101403
X0372799Y1098214
X0376500Y1098214
X0370949Y1095025
X0378351Y1095025
X0372799Y1091836
X0376500Y1085458
X0376500Y1155615
X0370949Y1152426
X0370949Y1082269
X0378351Y1152426
X0372799Y1149237
X0376500Y1142859
X0370949Y1139670
X0378351Y1139670
X0372799Y1136481
X0376500Y1136481
X0370949Y1133293
X0378351Y1133293
X0372799Y1130103
X0378351Y1082269
X0376500Y1123726
X0370949Y1120537
X0378351Y1120537
X0372799Y1117348
X0376500Y1117348
X0370949Y1114159
X0378351Y1114159
X0372799Y1110970
X0376500Y1104592
X0370949Y1101403
X0372799Y1079080
X0370949Y1050379
X0376500Y1047190
X0376500Y1066324
X0370949Y1063135
X0378351Y1063135
X0372799Y1059946
X0376500Y1079080
X0370949Y1075891
X0378351Y1075891
X0372799Y1072702
X0372799Y1040812
X0376500Y1040812
X0378351Y1037623
X0370949Y1037623
X0372799Y1034434
X0376500Y1034434
X0378351Y1031245
X0378351Y1050379
X0377169Y1007183
X0377169Y0975293
X0377169Y0956159
R02Y-0019134
X0377169Y0898758
X0369768Y0968915
R03Y-0019134
X0369768Y0892380
X0375319Y0972104
R03Y-0019134
X0375319Y0895569
X0371618Y0972104
R03Y-0019134
X0371618Y0895569
X0375319Y0908325
X0369768Y0905135
X0377169Y0905135
X0371618Y0901947
X0375319Y0901947
X0369768Y0898758
X0377169Y0892380
X0377169Y0962537
X0371618Y0959348
X0371618Y0889191
X0375319Y0959348
X0369768Y0956159
X0377169Y0949781
X0371618Y0946592
X0375319Y0946592
X0369768Y0943403
X0377169Y0943403
X0371618Y0940214
X0375319Y0940214
X0369768Y0937025
X0375319Y0889191
X0377169Y0930647
X0371618Y0927458
X0375319Y0927458
X0369768Y0924269
X0377169Y0924269
X0371618Y0921080
X0375319Y0921080
X0369768Y0917891
X0377169Y0911513
X0371618Y0908325
X0369768Y0886002
X0377169Y0994427
X0371618Y0991238
X0377169Y0981671
X0371618Y0978482
X0375319Y0978482
X0369768Y0975293
X0377169Y0968915
X0371618Y0965726
X0375319Y0965726
X0369768Y0962537
X0375319Y1003994
X0371618Y1003994
X0369768Y1000805
X0377169Y1000805
X0375319Y0997616
X0371618Y0997616
X0369768Y0994427
X0377169Y0988049
X0369768Y1007183
X0371618Y1010372
X0375319Y0984860
X1348941Y1053567
X1347091Y1044000
X1348941Y1066323
X1352642Y1149236
X1352642Y1130102
X1352642Y1110969
R02Y-0019134
X1348941Y1142858
X1348941Y1123725
X1348941Y1104591
X1348941Y1085457
X1347091Y1069512
X1354493Y1146047
X1354493Y1126914
X1354493Y1107780
R02Y-0019134
X1347091Y1146047
X1347091Y1126914
X1347091Y1107780
X1347091Y1088646
X1354493Y1101402
X1348941Y1098213
X1352642Y1098213
X1347091Y1095024
X1354493Y1095024
X1348941Y1091835
X1352642Y1085457
X1352642Y1155614
X1347091Y1152425
X1347091Y1082268
X1354493Y1152425
X1348941Y1149236
X1352642Y1142858
X1347091Y1139669
X1354493Y1139669
X1348941Y1136480
X1352642Y1136480
X1347091Y1133292
X1354493Y1133292
X1348941Y1130102
X1354493Y1082268
X1352642Y1123725
X1347091Y1120536
X1354493Y1120536
X1348941Y1117347
X1352642Y1117347
X1347091Y1114158
X1354493Y1114158
X1348941Y1110969
X1352642Y1104591
X1347091Y1101402
X1348941Y1079079
X1347091Y1050378
X1352642Y1047189
X1352642Y1066323
X1347091Y1063134
X1354493Y1063134
X1348941Y1059945
X1352642Y1079079
X1347091Y1075890
X1354493Y1075890
X1348941Y1072701
X1348941Y1040811
X1352642Y1040811
X1354493Y1037622
X1347091Y1037622
X1348941Y1034433
X1352642Y1034433
X1354493Y1031244
X1354493Y1050378
X1353311Y1007182
X1353311Y0975292
X1353311Y0956158
R02Y-0019134
X1353311Y0898757
X1345910Y0968914
R03Y-0019134
X1345910Y0892379
X1351461Y0972103
R03Y-0019134
X1351461Y0895568
X1347760Y0972103
R03Y-0019134
X1347760Y0895568
X1351461Y0908324
X1345910Y0905134
X1353311Y0905134
X1347760Y0901946
X1351461Y0901946
X1345910Y0898757
X1353311Y0892379
X1353311Y0962536
X1347760Y0959347
X1347760Y0889190
X1351461Y0959347
X1345910Y0956158
X1353311Y0949780
X1347760Y0946591
X1351461Y0946591
X1345910Y0943402
X1353311Y0943402
X1347760Y0940213
X1351461Y0940213
X1345910Y0937024
X1351461Y0889190
X1353311Y0930646
X1347760Y0927457
X1351461Y0927457
X1345910Y0924268
X1353311Y0924268
X1347760Y0921079
X1351461Y0921079
X1345910Y0917890
X1353311Y0911512
X1347760Y0908324
X1345910Y0886001
X1353311Y0994426
X1347760Y0991237
X1353311Y0981670
X1347760Y0978481
X1351461Y0978481
X1345910Y0975292
X1353311Y0968914
X1347760Y0965725
X1351461Y0965725
X1345910Y0962536
X1351461Y1003993
X1347760Y1003993
X1345910Y1000804
X1353311Y1000804
X1351461Y0997615
X1347760Y0997615
X1345910Y0994426
X1353311Y0988048
X1345910Y1007182
X1347760Y1010371
X1351461Y0984859
X0406776Y0905135
X1449507Y0905134
X0406776Y0892380
X1449507Y0892379
X0406776Y0898758
X1449507Y0898757
X0395673Y0905135
X1460609Y0905134
X0395673Y0892380
X1460609Y0892379
X0395673Y0898758
X1460609Y0898757
X0384571Y0905135
X1471712Y0905134
X0384571Y0892380
X1471712Y0892379
X0384571Y0898758
X1471712Y0898757
X0427130Y0908325
X1429153Y0908324
X0427130Y0901947
X1429153Y0901946
X0427130Y0895569
X1429153Y0895568
X0417878Y0905135
X1438405Y0905134
X0417878Y0892380
X1438405Y0892379
X0417878Y0898758
X1438405Y0898757
X0384571Y0911513
X1471712Y0911512
X0410477Y0905135
X1445806Y0905134
X0410477Y0892380
X1445806Y0892379
X0410477Y0898758
X1445806Y0898757
X0399374Y0905135
X1456909Y0905134
X0399374Y0892380
X1456909Y0892379
X0399374Y0898758
X1456909Y0898757
X0388272Y0905135
X1468011Y0905134
X0388272Y0892380
X1468011Y0892379
X0388272Y0898758
X1468011Y0898757
X0430831Y0908325
X1425452Y0908324
X0430831Y0901947
X1425452Y0901946
X0430831Y0895569
X1425452Y0895568
X0421579Y0905135
X1434704Y0905134
X0421579Y0892380
X1434704Y0892379
X0421579Y0898758
X1434704Y0898757
X0388272Y0911513
X1468011Y0911512
M00
X0452102Y0088711
X0472895Y0130020
X0476295Y0130020
X0455502Y0088711
X1436263Y-0021711
X1245840Y-0021711
X1436263Y-0018311
X1245840Y-0018311
X0725925Y-0022171
X0390841Y-0022171
X0725925Y-0025571
X0390841Y-0025571
X0704771Y0215032
R03Y-0011811
X0704771Y0218432
R03Y-0011811
X1007587Y0808818
X1007587Y0819752
X1007587Y0830754
X1007587Y0841756
X1007587Y0805418
X1007587Y0816352
X1007587Y0827354
X1007587Y0838356
X0109073Y1660235
X0112473Y1660235
X0110969Y1685763
X0107569Y1685763
X0722898Y1064706
X0706756Y1051320
X0722898Y1084785
X0706756Y1238722
R04Y-0036811
X0722898Y1232029
R03Y-0036811
X0722898Y1088131
X0706756Y1235375
R04Y-0036811
X0722898Y1235375
R03Y-0036811
X0722898Y1151714
X0722898Y1145021
X0706756Y1141675
X0706756Y1134982
X0722898Y1138328
X0722898Y1131635
X0706756Y1118249
X0706756Y1252108
X0706756Y1245415
X0706756Y1111556
X0722898Y1248761
X0722898Y1242068
X0706756Y1228682
X0706756Y1221989
X0722898Y1225336
X0722898Y1218643
X0706756Y1215297
X0706756Y1208604
X0722898Y1211950
X0722898Y1205257
X0722898Y1114903
X0706756Y1191871
X0706756Y1185178
X0722898Y1188525
X0722898Y1181832
X0706756Y1178486
X0706756Y1171793
X0722898Y1175139
X0722898Y1168446
X0706756Y1155060
X0706756Y1148367
X0722898Y1108210
X0706756Y1058013
X0722898Y1054667
X0706756Y1081438
X0706756Y1074745
X0722898Y1078092
X0722898Y1071399
X0706756Y1104863
X0706756Y1098171
X0722898Y1101517
X0722898Y1094824
X0722898Y1047974
X0706756Y1044627
X0722898Y1041281
X0706756Y1037934
X0722898Y1034588
X0706756Y1031241
X0722898Y1027895
X0722898Y1061360
X0722898Y1001123
X0706756Y0944234
X0706756Y0907423
X0706756Y0870611
R02Y-0036811
X0722898Y0937541
R04Y-0036811
X0706756Y0940887
R04Y-0036811
X0722898Y0940887
R04Y-0036811
X0722898Y0820415
X0722898Y0813722
X0706756Y0810375
X0706756Y0803682
X0722898Y0807029
X0722898Y0800336
X0706756Y0786950
X0706756Y0920808
X0706756Y0914115
X0706756Y0780257
X0722898Y0917462
X0722898Y0910769
X0706756Y0897383
X0706756Y0890690
X0722898Y0894037
X0722898Y0887344
X0706756Y0883997
X0706756Y0877304
X0722898Y0880651
X0722898Y0873958
X0722898Y0783604
X0706756Y0860572
X0706756Y0853879
X0722898Y0857226
X0722898Y0850533
X0706756Y0847186
X0706756Y0840493
X0722898Y0843840
X0722898Y0837147
X0706756Y0823761
X0706756Y0817068
X0722898Y0776911
X0706756Y0971005
X0722898Y0967659
X0706756Y0957619
X0706756Y0950926
X0722898Y0954273
X0722898Y0947580
X0706756Y0934194
X0706756Y0927501
X0722898Y0930848
X0722898Y0924155
X0722898Y0994430
X0706756Y0991084
X0722898Y0987737
X0706756Y0984391
X0722898Y0981045
X0706756Y0977698
X0722898Y0974352
X0706756Y0964312
X0706756Y0997777
X0706756Y1001123
X1699040Y1064705
X1682898Y1051319
X1699040Y1084784
X1682898Y1238721
R04Y-0036811
X1699040Y1232028
R03Y-0036811
X1699040Y1088130
X1682898Y1235374
R04Y-0036811
X1699040Y1235374
R03Y-0036811
X1699040Y1151713
X1699040Y1145020
X1682898Y1141674
X1682898Y1134981
X1699040Y1138327
X1699040Y1131634
X1682898Y1118248
X1682898Y1252107
X1682898Y1245414
X1682898Y1111555
X1699040Y1248760
X1699040Y1242067
X1682898Y1228681
X1682898Y1221988
X1699040Y1225335
X1699040Y1218642
X1682898Y1215296
X1682898Y1208603
X1699040Y1211949
X1699040Y1205256
X1699040Y1114902
X1682898Y1191870
X1682898Y1185177
X1699040Y1188524
X1699040Y1181831
X1682898Y1178485
X1682898Y1171792
X1699040Y1175138
X1699040Y1168445
X1682898Y1155059
X1682898Y1148366
X1699040Y1108209
X1682898Y1058012
X1699040Y1054666
X1682898Y1081437
X1682898Y1074744
X1699040Y1078091
X1699040Y1071398
X1682898Y1104862
X1682898Y1098170
X1699040Y1101516
X1699040Y1094823
X1699040Y1047973
X1682898Y1044626
X1699040Y1041280
X1682898Y1037933
X1699040Y1034587
X1682898Y1031240
X1699040Y1027894
X1699040Y1061359
X1699040Y1001122
X1682898Y0944233
X1682898Y0907422
X1682898Y0870610
R02Y-0036811
X1699040Y0937540
R04Y-0036811
X1682898Y0940886
R04Y-0036811
X1699040Y0940886
R04Y-0036811
X1699040Y0820414
X1699040Y0813721
X1682898Y0810374
X1682898Y0803681
X1699040Y0807028
X1699040Y0800335
X1682898Y0786949
X1682898Y0920807
X1682898Y0914114
X1682898Y0780256
X1699040Y0917461
X1699040Y0910768
X1682898Y0897382
X1682898Y0890689
X1699040Y0894036
X1699040Y0887343
X1682898Y0883996
X1682898Y0877303
X1699040Y0880650
X1699040Y0873957
X1699040Y0783603
X1682898Y0860571
X1682898Y0853878
X1699040Y0857225
X1699040Y0850532
X1682898Y0847185
X1682898Y0840492
X1699040Y0843839
X1699040Y0837146
X1682898Y0823760
X1682898Y0817067
X1699040Y0776910
X1682898Y0971004
X1699040Y0967658
X1682898Y0957618
X1682898Y0950925
X1699040Y0954272
X1699040Y0947579
X1682898Y0934193
X1682898Y0927500
X1699040Y0930847
X1699040Y0924154
X1699040Y0994429
X1682898Y0991083
X1699040Y0987736
X1682898Y0984390
X1699040Y0981044
X1682898Y0977697
X1699040Y0974351
X1682898Y0964311
X1682898Y0997776
X1682898Y1001122
X0174567Y1064706
X0158425Y1051320
X0174567Y1084785
X0158425Y1238722
R04Y-0036811
X0174567Y1232029
R03Y-0036811
X0174567Y1088131
X0158425Y1235375
R04Y-0036811
X0174567Y1235375
R03Y-0036811
X0174567Y1151714
X0174567Y1145021
X0158425Y1141675
X0158425Y1134982
X0174567Y1138328
X0174567Y1131635
X0158425Y1118249
X0158425Y1252108
X0158425Y1245415
X0158425Y1111556
X0174567Y1248761
X0174567Y1242068
X0158425Y1228682
X0158425Y1221989
X0174567Y1225336
X0174567Y1218643
X0158425Y1215297
X0158425Y1208604
X0174567Y1211950
X0174567Y1205257
X0174567Y1114903
X0158425Y1191871
X0158425Y1185178
X0174567Y1188525
X0174567Y1181832
X0158425Y1178486
X0158425Y1171793
X0174567Y1175139
X0174567Y1168446
X0158425Y1155060
X0158425Y1148367
X0174567Y1108210
X0158425Y1058013
X0174567Y1054667
X0158425Y1081438
X0158425Y1074745
X0174567Y1078092
X0174567Y1071399
X0158425Y1104863
X0158425Y1098171
X0174567Y1101517
X0174567Y1094824
X0174567Y1047974
X0158425Y1044627
X0174567Y1041281
X0158425Y1037934
X0174567Y1034588
X0158425Y1031241
X0174567Y1027895
X0174567Y1061360
X0174567Y1001123
X0158425Y0944234
X0158425Y0907423
X0158425Y0870611
R02Y-0036811
X0174567Y0937541
R04Y-0036811
X0158425Y0940887
R04Y-0036811
X0174567Y0940887
R04Y-0036811
X0174567Y0820415
X0174567Y0813722
X0158425Y0810375
X0158425Y0803682
X0174567Y0807029
X0174567Y0800336
X0158425Y0786950
X0158425Y0920808
X0158425Y0914115
X0158425Y0780257
X0174567Y0917462
X0174567Y0910769
X0158425Y0897383
X0158425Y0890690
X0174567Y0894037
X0174567Y0887344
X0158425Y0883997
X0158425Y0877304
X0174567Y0880651
X0174567Y0873958
X0174567Y0783604
X0158425Y0860572
X0158425Y0853879
X0174567Y0857226
X0174567Y0850533
X0158425Y0847186
X0158425Y0840493
X0174567Y0843840
X0174567Y0837147
X0158425Y0823761
X0158425Y0817068
X0174567Y0776911
X0158425Y0971005
X0174567Y0967659
X0158425Y0957619
X0158425Y0950926
X0174567Y0954273
X0174567Y0947580
X0158425Y0934194
X0158425Y0927501
X0174567Y0930848
X0174567Y0924155
X0174567Y0994430
X0158425Y0991084
X0174567Y0987737
X0158425Y0984391
X0174567Y0981045
X0158425Y0977698
X0174567Y0974352
X0158425Y0964312
X0158425Y0997777
X0158425Y1001123
X1150709Y1064705
X1134567Y1051319
X1150709Y1084784
X1134567Y1238721
R04Y-0036811
X1150709Y1232028
R03Y-0036811
X1150709Y1088130
X1134567Y1235374
R04Y-0036811
X1150709Y1235374
R03Y-0036811
X1150709Y1151713
X1150709Y1145020
X1134567Y1141674
X1134567Y1134981
X1150709Y1138327
X1150709Y1131634
X1134567Y1118248
X1134567Y1252107
X1134567Y1245414
X1134567Y1111555
X1150709Y1248760
X1150709Y1242067
X1134567Y1228681
X1134567Y1221988
X1150709Y1225335
X1150709Y1218642
X1134567Y1215296
X1134567Y1208603
X1150709Y1211949
X1150709Y1205256
X1150709Y1114902
X1134567Y1191870
X1134567Y1185177
X1150709Y1188524
X1150709Y1181831
X1134567Y1178485
X1134567Y1171792
X1150709Y1175138
X1150709Y1168445
X1134567Y1155059
X1134567Y1148366
X1150709Y1108209
X1134567Y1058012
X1150709Y1054666
X1134567Y1081437
X1134567Y1074744
X1150709Y1078091
X1150709Y1071398
X1134567Y1104862
X1134567Y1098170
X1150709Y1101516
X1150709Y1094823
X1150709Y1047973
X1134567Y1044626
X1150709Y1041280
X1134567Y1037933
X1150709Y1034587
X1134567Y1031240
X1150709Y1027894
X1150709Y1061359
X1150709Y1001122
X1134567Y0944233
X1134567Y0907422
X1134567Y0870610
R02Y-0036811
X1150709Y0937540
R04Y-0036811
X1134567Y0940886
R04Y-0036811
X1150709Y0940886
R04Y-0036811
X1150709Y0820414
X1150709Y0813721
X1134567Y0810374
X1134567Y0803681
X1150709Y0807028
X1150709Y0800335
X1134567Y0786949
X1134567Y0920807
X1134567Y0914114
X1134567Y0780256
X1150709Y0917461
X1150709Y0910768
X1134567Y0897382
X1134567Y0890689
X1150709Y0894036
X1150709Y0887343
X1134567Y0883996
X1134567Y0877303
X1150709Y0880650
X1150709Y0873957
X1150709Y0783603
X1134567Y0860571
X1134567Y0853878
X1150709Y0857225
X1150709Y0850532
X1134567Y0847185
X1134567Y0840492
X1150709Y0843839
X1150709Y0837146
X1134567Y0823760
X1134567Y0817067
X1150709Y0776910
X1134567Y0971004
X1150709Y0967658
X1134567Y0957618
X1134567Y0950925
X1150709Y0954272
X1150709Y0947579
X1134567Y0934193
X1134567Y0927500
X1150709Y0930847
X1150709Y0924154
X1150709Y0994429
X1134567Y0991083
X1150709Y0987736
X1134567Y0984390
X1150709Y0981044
X1134567Y0977697
X1150709Y0974351
X1134567Y0964311
X1134567Y0997776
X1134567Y1001122
M30
